# BASEBOARD_FAB2 (Tioga Pass) — schematic netlist excerpt (pin names and nets, part order shuffled) for the footprints in the layout excerpt that follows; sources: Cadence DE-HDL packaged netlist, KiCad conversion of Wiwynn_Tioga_Pass_MB.brd

C25W31  CAP_A  0.1UF 16V 10% X7R  pkg 0402V  page 149 : A = VCC_ADCAV3V3 ; B = GND
C5T9  CAP_A  47UF 4V 20% X5R  pkg 0603V  page 217 : A = PVDDQ_ABC ; B = GND
C8T8  CAP_A  47UF 4V 20% X5R  pkg 0603V  page 225 : A = PVDDQ_GHJ ; B = GND

(kicad_pcb
	(version 20260206)
	(generator "pcbnew")
	(generator_version "10.0")
	(general
		(thickness 1.6)
		(legacy_teardrops no)
	)
	(paper "A4")
	(title_block
		(title "Wiwynn_Tioga_Pass_MB.brd")
		(comment 1 "Tioga Pass / footprints 2591-2593 of 4770")
	)
	(layers
		(0 "F.Cu" signal "TOP")
		(4 "In1.Cu" signal "L2GND")
		(6 "In2.Cu" signal "L3")
		(8 "In3.Cu" signal "L4GND")
		(10 "In4.Cu" signal "L5")
		(12 "In5.Cu" signal "L6GND")
		(14 "In6.Cu" signal "L7VCC")
		(16 "In7.Cu" signal "L8VCC")
		(18 "In8.Cu" signal "L9GND")
		(20 "In9.Cu" signal "L10")
		(22 "In10.Cu" signal "L11GND")
		(24 "In11.Cu" signal "L12")
		(26 "In12.Cu" signal "L13GND")
		(2 "B.Cu" signal "BOTTOM")
		(9 "F.Adhes" user "F.Adhesive")
		(11 "B.Adhes" user "B.Adhesive")
		(13 "F.Paste" user "Package Geometry/Pastemask Top")
		(15 "B.Paste" user "Package Geometry/Pastemask Bottom")
		(5 "F.SilkS" user "Ref Des/Silkscreen Top")
		(7 "B.SilkS" user "Ref Des/Silkscreen Bottom")
		(1 "F.Mask" user "Board Geometry/Soldermask Top")
		(3 "B.Mask" user "Board Geometry/Soldermask Bottom")
		(17 "Dwgs.User" user "User.Drawings")
		(19 "Cmts.User" user "User.Comments")
		(21 "Eco1.User" user "User.Eco1")
		(23 "Eco2.User" user "User.Eco2")
		(25 "Edge.Cuts" user "Board Geometry/Outline")
		(27 "Margin" user)
		(31 "F.CrtYd" user "Package Geometry/Place Bound Top")
		(29 "B.CrtYd" user "Package Geometry/Place Bound Bottom")
		(35 "F.Fab" user "Ref Des/Assembly Top")
		(33 "B.Fab" user "Ref Des/Assembly Bottom")
	)
	(footprint ""
		(layer "B.Cu")
		(at 87.158068 -17.7546 -90)
		(property "Reference" "C8T8"
			(at -1.848866 0.752348 270)
			(unlocked yes)
			(layer "B.SilkS")
			(effects
				(font
					(size 1.27 0.9652)
					(thickness 0.1524)
				)
				(justify mirror)
			)
		)
		(property "Value" ""
			(at 0 0 90)
			(layer "B.Fab")
			(effects
				(font
					(size 1.27 1.27)
				)
				(justify mirror)
			)
		)
		(duplicate_pad_numbers_are_jumpers no)
		(fp_rect
			(start 0.500126 1.598422)
			(end -0.500126 -0.201422)
			(stroke
				(width 0)
				(type default)
			)
			(fill no)
			(layer "B.CrtYd")
		)
		(fp_line
			(start -0.500126 1.598422)
			(end 0.500126 1.598422)
			(stroke
				(width 0.1)
				(type default)
			)
			(layer "B.Fab")
		)
		(fp_line
			(start 0.500126 1.598422)
			(end 0.500126 -0.201422)
			(stroke
				(width 0.1)
				(type default)
			)
			(layer "B.Fab")
		)
		(fp_line
			(start -0.500126 -0.201422)
			(end -0.500126 1.598422)
			(stroke
				(width 0.1)
				(type default)
			)
			(layer "B.Fab")
		)
		(fp_line
			(start 0.500126 -0.201422)
			(end -0.500126 -0.201422)
			(stroke
				(width 0.1)
				(type default)
			)
			(layer "B.Fab")
		)
		(pad "1" smd rect
			(at 0 0 180)
			(size 0.889 0.9906)
			(layers "B.Cu" "B.Mask" "B.Paste")
			(net "PVDDQ_GHJ")
		)
		(pad "2" smd rect
			(at 0 1.397 180)
			(size 0.889 0.9906)
			(layers "B.Cu" "B.Mask" "B.Paste")
			(net "GND")
		)
		(zone
			(layer "B.Cu")
			(hatch none 0.5)
			(connect_pads
				(clearance 0)
			)
			(min_thickness 0.25)
			(keepout
				(tracks allowed)
				(vias not_allowed)
				(pads allowed)
				(copperpour not_allowed)
				(footprints allowed)
			)
			(placement
				(enabled no)
				(sheetname "")
			)
			(fill
				(thermal_gap 0.5)
				(thermal_bridge_width 0.5)
				(island_removal_mode 0)
			)
			(polygon
				(pts
					(xy 86.205568 -17.2593) (xy 86.713568 -17.2593) (xy 86.713568 -18.2499) (xy 86.205568 -18.2499)
				)
			)
		)
		(zone
			(layer "B.Cu")
			(hatch none 0.5)
			(connect_pads
				(clearance 0)
			)
			(min_thickness 0.25)
			(keepout
				(tracks not_allowed)
				(vias allowed)
				(pads allowed)
				(copperpour not_allowed)
				(footprints allowed)
			)
			(placement
				(enabled no)
				(sheetname "")
			)
			(fill
				(thermal_gap 0.5)
				(thermal_bridge_width 0.5)
				(island_removal_mode 0)
			)
			(polygon
				(pts
					(xy 86.205568 -17.2593) (xy 86.713568 -17.2593) (xy 86.713568 -18.2499) (xy 86.205568 -18.2499)
				)
			)
		)
	)
	(footprint ""
		(layer "B.Cu")
		(at 413.0675 -26.162 -90)
		(property "Reference" "C25W31"
			(at 0.8382 -0.67818 270)
			(unlocked yes)
			(layer "B.SilkS")
			(effects
				(font
					(size 0.4064 0.254)
					(thickness 0.1524)
				)
				(justify left mirror)
			)
		)
		(property "Value" ""
			(at 0 0 90)
			(layer "B.Fab")
			(effects
				(font
					(size 1.27 1.27)
				)
				(justify mirror)
			)
		)
		(duplicate_pad_numbers_are_jumpers no)
		(fp_poly
			(pts
				(xy -0.3048 -0.1016) (xy -0.3048 0.9906) (xy 0.3048 0.9906) (xy 0.3048 -0.1016)
			)
			(stroke
				(width 0)
				(type default)
			)
			(fill no)
			(layer "B.CrtYd")
		)
		(fp_line
			(start -0.3048 0.9906)
			(end -0.3048 -0.1016)
			(stroke
				(width 0.1)
				(type default)
			)
			(layer "B.Fab")
		)
		(fp_line
			(start 0.3048 0.9906)
			(end -0.3048 0.9906)
			(stroke
				(width 0.1)
				(type default)
			)
			(layer "B.Fab")
		)
		(fp_line
			(start -0.3048 -0.1016)
			(end 0.3048 -0.1016)
			(stroke
				(width 0.1)
				(type default)
			)
			(layer "B.Fab")
		)
		(fp_line
			(start 0.3048 -0.1016)
			(end 0.3048 0.9906)
			(stroke
				(width 0.1)
				(type default)
			)
			(layer "B.Fab")
		)
		(pad "1" smd rect
			(at 0 0 90)
			(size 0.508 0.508)
			(layers "B.Cu" "B.Mask" "B.Paste")
			(net "VCC_ADCAV3V3")
		)
		(pad "2" smd rect
			(at 0 0.889 90)
			(size 0.508 0.508)
			(layers "B.Cu" "B.Mask" "B.Paste")
			(net "GND")
		)
		(zone
			(layer "B.Cu")
			(hatch none 0.5)
			(connect_pads
				(clearance 0)
			)
			(min_thickness 0.25)
			(keepout
				(tracks not_allowed)
				(vias allowed)
				(pads allowed)
				(copperpour not_allowed)
				(footprints allowed)
			)
			(placement
				(enabled no)
				(sheetname "")
			)
			(fill
				(thermal_gap 0.5)
				(thermal_bridge_width 0.5)
				(island_removal_mode 0)
			)
			(polygon
				(pts
					(xy 412.4325 -25.908) (xy 412.4325 -26.416) (xy 412.8135 -26.416) (xy 412.8135 -25.908)
				)
			)
		)
		(zone
			(layer "B.Cu")
			(hatch none 0.5)
			(connect_pads
				(clearance 0)
			)
			(min_thickness 0.25)
			(keepout
				(tracks allowed)
				(vias not_allowed)
				(pads allowed)
				(copperpour not_allowed)
				(footprints allowed)
			)
			(placement
				(enabled no)
				(sheetname "")
			)
			(fill
				(thermal_gap 0.5)
				(thermal_bridge_width 0.5)
				(island_removal_mode 0)
			)
			(polygon
				(pts
					(xy 412.8135 -25.908) (xy 412.8135 -26.416) (xy 412.4325 -26.416) (xy 412.4325 -25.908)
				)
			)
		)
	)
	(footprint ""
		(layer "B.Cu")
		(at 253.392432 -17.7546 90)
		(property "Reference" "C5T9"
			(at -1.848866 0.752348 90)
			(unlocked yes)
			(layer "B.SilkS")
			(effects
				(font
					(size 1.27 0.9652)
					(thickness 0.1524)
				)
				(justify mirror)
			)
		)
		(property "Value" ""
			(at 0 0 90)
			(layer "B.Fab")
			(effects
				(font
					(size 1.27 1.27)
				)
				(justify mirror)
			)
		)
		(duplicate_pad_numbers_are_jumpers no)
		(fp_rect
			(start 0.500126 1.598422)
			(end -0.500126 -0.201422)
			(stroke
				(width 0)
				(type default)
			)
			(fill no)
			(layer "B.CrtYd")
		)
		(fp_line
			(start 0.500126 -0.201422)
			(end -0.500126 -0.201422)
			(stroke
				(width 0.1)
				(type default)
			)
			(layer "B.Fab")
		)
		(fp_line
			(start -0.500126 -0.201422)
			(end -0.500126 1.598422)
			(stroke
				(width 0.1)
				(type default)
			)
			(layer "B.Fab")
		)
		(fp_line
			(start 0.500126 1.598422)
			(end 0.500126 -0.201422)
			(stroke
				(width 0.1)
				(type default)
			)
			(layer "B.Fab")
		)
		(fp_line
			(start -0.500126 1.598422)
			(end 0.500126 1.598422)
			(stroke
				(width 0.1)
				(type default)
			)
			(layer "B.Fab")
		)
		(pad "1" smd rect
			(at 0 0)
			(size 0.889 0.9906)
			(layers "B.Cu" "B.Mask" "B.Paste")
			(net "PVDDQ_ABC")
		)
		(pad "2" smd rect
			(at 0 1.397)
			(size 0.889 0.9906)
			(layers "B.Cu" "B.Mask" "B.Paste")
			(net "GND")
		)
		(zone
			(layer "B.Cu")
			(hatch none 0.5)
			(connect_pads
				(clearance 0)
			)
			(min_thickness 0.25)
			(keepout
				(tracks allowed)
				(vias not_allowed)
				(pads allowed)
				(copperpour not_allowed)
				(footprints allowed)
			)
			(placement
				(enabled no)
				(sheetname "")
			)
			(fill
				(thermal_gap 0.5)
				(thermal_bridge_width 0.5)
				(island_removal_mode 0)
			)
			(polygon
				(pts
					(xy 254.344932 -18.2499) (xy 253.836932 -18.2499) (xy 253.836932 -17.2593) (xy 254.344932 -17.2593)
				)
			)
		)
		(zone
			(layer "B.Cu")
			(hatch none 0.5)
			(connect_pads
				(clearance 0)
			)
			(min_thickness 0.25)
			(keepout
				(tracks not_allowed)
				(vias allowed)
				(pads allowed)
				(copperpour not_allowed)
				(footprints allowed)
			)
			(placement
				(enabled no)
				(sheetname "")
			)
			(fill
				(thermal_gap 0.5)
				(thermal_bridge_width 0.5)
				(island_removal_mode 0)
			)
			(polygon
				(pts
					(xy 254.344932 -18.2499) (xy 253.836932 -18.2499) (xy 253.836932 -17.2593) (xy 254.344932 -17.2593)
				)
			)
		)
	)
)
